(kicad_pcb
	(version 20260206)
	(generator "pcbnew")
	(generator_version "10.0")
	(general
		(thickness 1.6)
		(legacy_teardrops no)
	)
	(paper "A4")
	(title_block
		(title "12092022_DA0F0TMDCD0_F0T_Management_Board_D_brd_V3_OCP.brd")
		(comment 1 "Grand Teton / footprints 231-236 of 1440")
	)
	(layers
		(0 "F.Cu" signal "TOP")
		(4 "In1.Cu" signal "GND")
		(6 "In2.Cu" signal "IN1")
		(8 "In3.Cu" signal "GND1")
		(10 "In4.Cu" signal "IN2")
		(12 "In5.Cu" signal "VCC")
		(14 "In6.Cu" signal "VCC1")
		(16 "In7.Cu" signal "IN3")
		(18 "In8.Cu" signal "GND2")
		(20 "In9.Cu" signal "IN4")
		(22 "In10.Cu" signal "GND3")
		(2 "B.Cu" signal "BOTTOM")
		(9 "F.Adhes" user "F.Adhesive")
		(11 "B.Adhes" user "B.Adhesive")
		(13 "F.Paste" user "Package Geometry/Pastemask Top")
		(15 "B.Paste" user "Package Geometry/Pastemask Bottom")
		(5 "F.SilkS" user "Ref Des/Silkscreen Top")
		(7 "B.SilkS" user "Ref Des/Silkscreen Bottom")
		(1 "F.Mask" user "Board Geometry/Soldermask Top")
		(3 "B.Mask" user "Board Geometry/Soldermask Bottom")
		(17 "Dwgs.User" user "User.Drawings")
		(19 "Cmts.User" user "User.Comments")
		(21 "Eco1.User" user "User.Eco1")
		(23 "Eco2.User" user "User.Eco2")
		(25 "Edge.Cuts" user "Board Geometry/Outline")
		(27 "Margin" user)
		(31 "F.CrtYd" user "Package Geometry/Place Bound Top")
		(29 "B.CrtYd" user "Package Geometry/Place Bound Bottom")
		(35 "F.Fab" user "Ref Des/Assembly Top")
		(33 "B.Fab" user "Ref Des/Assembly Bottom")
	)
	(footprint ""
		(layer "F.Cu")
		(at 16.50365 -29.5783 180)
		(property "Reference" "PR543"
			(at 0 0 180)
			(layer "F.SilkS")
			(hide yes)
			(effects
				(font
					(size 1.27 1.27)
				)
			)
		)
		(property "Value" ""
			(at 0 0 180)
			(layer "F.Fab")
			(effects
				(font
					(size 1.27 1.27)
				)
			)
		)
		(duplicate_pad_numbers_are_jumpers no)
		(fp_line
			(start 0.7874 0.4064)
			(end -0.7874 0.4064)
			(stroke
				(width 0.1524)
				(type default)
			)
			(layer "F.SilkS")
		)
		(fp_line
			(start 0.7874 -0.4064)
			(end 0.7874 0.4064)
			(stroke
				(width 0.1524)
				(type default)
			)
			(layer "F.SilkS")
		)
		(fp_line
			(start -0.7874 0.4064)
			(end -0.7874 -0.4064)
			(stroke
				(width 0.1524)
				(type default)
			)
			(layer "F.SilkS")
		)
		(fp_line
			(start -0.7874 -0.4064)
			(end 0.7874 -0.4064)
			(stroke
				(width 0.1524)
				(type default)
			)
			(layer "F.SilkS")
		)
		(fp_line
			(start 0.67945 0.3048)
			(end 0.120396 0.3048)
			(stroke
				(width 0.1)
				(type default)
			)
			(layer "F.Fab")
		)
		(fp_line
			(start 0.67945 -0.3048)
			(end 0.67945 0.3048)
			(stroke
				(width 0.1)
				(type default)
			)
			(layer "F.Fab")
		)
		(fp_line
			(start 0.12065 -0.2794)
			(end 0.12065 -0.3048)
			(stroke
				(width 0.1)
				(type default)
			)
			(layer "F.Fab")
		)
		(fp_line
			(start 0.12065 -0.3048)
			(end 0.67945 -0.3048)
			(stroke
				(width 0.1)
				(type default)
			)
			(layer "F.Fab")
		)
		(fp_line
			(start 0.120396 0.3048)
			(end 0.120396 0.2794)
			(stroke
				(width 0.1)
				(type default)
			)
			(layer "F.Fab")
		)
		(fp_line
			(start 0.120396 0.2794)
			(end -0.12065 0.2794)
			(stroke
				(width 0.1)
				(type default)
			)
			(layer "F.Fab")
		)
		(fp_line
			(start -0.12065 0.3048)
			(end -0.67945 0.3048)
			(stroke
				(width 0.1)
				(type default)
			)
			(layer "F.Fab")
		)
		(fp_line
			(start -0.12065 0.2794)
			(end -0.12065 0.3048)
			(stroke
				(width 0.1)
				(type default)
			)
			(layer "F.Fab")
		)
		(fp_line
			(start -0.12065 -0.2794)
			(end 0.12065 -0.2794)
			(stroke
				(width 0.1)
				(type default)
			)
			(layer "F.Fab")
		)
		(fp_line
			(start -0.12065 -0.305054)
			(end -0.12065 -0.2794)
			(stroke
				(width 0.1)
				(type default)
			)
			(layer "F.Fab")
		)
		(fp_line
			(start -0.67945 0.3048)
			(end -0.67945 -0.305054)
			(stroke
				(width 0.1)
				(type default)
			)
			(layer "F.Fab")
		)
		(fp_line
			(start -0.67945 -0.305054)
			(end -0.12065 -0.305054)
			(stroke
				(width 0.1)
				(type default)
			)
			(layer "F.Fab")
		)
		(pad "1" smd circle
			(at -0.40005 0 180)
			(size 0 0)
			(layers "F.Cu" "F.Mask" "F.Paste")
			(net "P1V0_AUX_MODE")
		)
		(pad "2" smd circle
			(at 0.40005 0 180)
			(size 0 0)
			(layers "F.Cu" "F.Mask" "F.Paste")
			(net "GND")
		)
	)
	(footprint ""
		(layer "F.Cu")
		(at 56.0324 -82.8802 -90)
		(property "Reference" "R554"
			(at 0 0 270)
			(layer "F.SilkS")
			(hide yes)
			(effects
				(font
					(size 1.27 1.27)
				)
			)
		)
		(property "Value" ""
			(at 0 0 270)
			(layer "F.Fab")
			(effects
				(font
					(size 1.27 1.27)
				)
			)
		)
		(duplicate_pad_numbers_are_jumpers no)
		(fp_line
			(start -0.7874 0.4064)
			(end -0.7874 -0.4064)
			(stroke
				(width 0.1524)
				(type default)
			)
			(layer "F.SilkS")
		)
		(fp_line
			(start 0.7874 0.4064)
			(end -0.7874 0.4064)
			(stroke
				(width 0.1524)
				(type default)
			)
			(layer "F.SilkS")
		)
		(fp_line
			(start -0.7874 -0.4064)
			(end 0.7874 -0.4064)
			(stroke
				(width 0.1524)
				(type default)
			)
			(layer "F.SilkS")
		)
		(fp_line
			(start 0.7874 -0.4064)
			(end 0.7874 0.4064)
			(stroke
				(width 0.1524)
				(type default)
			)
			(layer "F.SilkS")
		)
		(fp_line
			(start -0.67945 0.3048)
			(end -0.67945 -0.305054)
			(stroke
				(width 0.1)
				(type default)
			)
			(layer "F.Fab")
		)
		(fp_line
			(start -0.12065 0.3048)
			(end -0.67945 0.3048)
			(stroke
				(width 0.1)
				(type default)
			)
			(layer "F.Fab")
		)
		(fp_line
			(start 0.120396 0.3048)
			(end 0.120396 0.2794)
			(stroke
				(width 0.1)
				(type default)
			)
			(layer "F.Fab")
		)
		(fp_line
			(start 0.67945 0.3048)
			(end 0.120396 0.3048)
			(stroke
				(width 0.1)
				(type default)
			)
			(layer "F.Fab")
		)
		(fp_line
			(start -0.12065 0.2794)
			(end -0.12065 0.3048)
			(stroke
				(width 0.1)
				(type default)
			)
			(layer "F.Fab")
		)
		(fp_line
			(start 0.120396 0.2794)
			(end -0.12065 0.2794)
			(stroke
				(width 0.1)
				(type default)
			)
			(layer "F.Fab")
		)
		(fp_line
			(start -0.12065 -0.2794)
			(end 0.12065 -0.2794)
			(stroke
				(width 0.1)
				(type default)
			)
			(layer "F.Fab")
		)
		(fp_line
			(start 0.12065 -0.2794)
			(end 0.12065 -0.3048)
			(stroke
				(width 0.1)
				(type default)
			)
			(layer "F.Fab")
		)
		(fp_line
			(start 0.12065 -0.3048)
			(end 0.67945 -0.3048)
			(stroke
				(width 0.1)
				(type default)
			)
			(layer "F.Fab")
		)
		(fp_line
			(start 0.67945 -0.3048)
			(end 0.67945 0.3048)
			(stroke
				(width 0.1)
				(type default)
			)
			(layer "F.Fab")
		)
		(fp_line
			(start -0.67945 -0.305054)
			(end -0.12065 -0.305054)
			(stroke
				(width 0.1)
				(type default)
			)
			(layer "F.Fab")
		)
		(fp_line
			(start -0.12065 -0.305054)
			(end -0.12065 -0.2794)
			(stroke
				(width 0.1)
				(type default)
			)
			(layer "F.Fab")
		)
		(pad "1" smd circle
			(at -0.40005 0 270)
			(size 0 0)
			(layers "F.Cu" "F.Mask" "F.Paste")
			(net "P3V3_AUX")
		)
		(pad "2" smd circle
			(at 0.40005 0 270)
			(size 0 0)
			(layers "F.Cu" "F.Mask" "F.Paste")
			(net "FLASH_R_WP_STATUS")
		)
	)
	(footprint ""
		(layer "F.Cu")
		(at 54.61 -10.795 -90)
		(property "Reference" "R286"
			(at 0 0 270)
			(layer "F.SilkS")
			(hide yes)
			(effects
				(font
					(size 1.27 1.27)
				)
			)
		)
		(property "Value" ""
			(at 0 0 270)
			(layer "F.Fab")
			(effects
				(font
					(size 1.27 1.27)
				)
			)
		)
		(duplicate_pad_numbers_are_jumpers no)
		(fp_line
			(start -0.7874 0.4064)
			(end -0.7874 -0.4064)
			(stroke
				(width 0.1524)
				(type default)
			)
			(layer "F.SilkS")
		)
		(fp_line
			(start 0.7874 0.4064)
			(end -0.7874 0.4064)
			(stroke
				(width 0.1524)
				(type default)
			)
			(layer "F.SilkS")
		)
		(fp_line
			(start -0.7874 -0.4064)
			(end 0.7874 -0.4064)
			(stroke
				(width 0.1524)
				(type default)
			)
			(layer "F.SilkS")
		)
		(fp_line
			(start 0.7874 -0.4064)
			(end 0.7874 0.4064)
			(stroke
				(width 0.1524)
				(type default)
			)
			(layer "F.SilkS")
		)
		(fp_line
			(start -0.67945 0.3048)
			(end -0.67945 -0.305054)
			(stroke
				(width 0.1)
				(type default)
			)
			(layer "F.Fab")
		)
		(fp_line
			(start -0.12065 0.3048)
			(end -0.67945 0.3048)
			(stroke
				(width 0.1)
				(type default)
			)
			(layer "F.Fab")
		)
		(fp_line
			(start 0.120396 0.3048)
			(end 0.120396 0.2794)
			(stroke
				(width 0.1)
				(type default)
			)
			(layer "F.Fab")
		)
		(fp_line
			(start 0.67945 0.3048)
			(end 0.120396 0.3048)
			(stroke
				(width 0.1)
				(type default)
			)
			(layer "F.Fab")
		)
		(fp_line
			(start -0.12065 0.2794)
			(end -0.12065 0.3048)
			(stroke
				(width 0.1)
				(type default)
			)
			(layer "F.Fab")
		)
		(fp_line
			(start 0.120396 0.2794)
			(end -0.12065 0.2794)
			(stroke
				(width 0.1)
				(type default)
			)
			(layer "F.Fab")
		)
		(fp_line
			(start -0.12065 -0.2794)
			(end 0.12065 -0.2794)
			(stroke
				(width 0.1)
				(type default)
			)
			(layer "F.Fab")
		)
		(fp_line
			(start 0.12065 -0.2794)
			(end 0.12065 -0.3048)
			(stroke
				(width 0.1)
				(type default)
			)
			(layer "F.Fab")
		)
		(fp_line
			(start 0.12065 -0.3048)
			(end 0.67945 -0.3048)
			(stroke
				(width 0.1)
				(type default)
			)
			(layer "F.Fab")
		)
		(fp_line
			(start 0.67945 -0.3048)
			(end 0.67945 0.3048)
			(stroke
				(width 0.1)
				(type default)
			)
			(layer "F.Fab")
		)
		(fp_line
			(start -0.67945 -0.305054)
			(end -0.12065 -0.305054)
			(stroke
				(width 0.1)
				(type default)
			)
			(layer "F.Fab")
		)
		(fp_line
			(start -0.12065 -0.305054)
			(end -0.12065 -0.2794)
			(stroke
				(width 0.1)
				(type default)
			)
			(layer "F.Fab")
		)
		(pad "1" smd circle
			(at -0.40005 0 270)
			(size 0 0)
			(layers "F.Cu" "F.Mask" "F.Paste")
			(net "LED_D21_R2")
		)
		(pad "2" smd circle
			(at 0.40005 0 270)
			(size 0 0)
			(layers "F.Cu" "F.Mask" "F.Paste")
			(net "LED_D21_R1")
		)
	)
	(footprint ""
		(layer "F.Cu")
		(at 66.0146 -66.0146)
		(property "Reference" "R468"
			(at 0 0 0)
			(layer "F.SilkS")
			(hide yes)
			(effects
				(font
					(size 1.27 1.27)
				)
			)
		)
		(property "Value" ""
			(at 0 0 0)
			(layer "F.Fab")
			(effects
				(font
					(size 1.27 1.27)
				)
			)
		)
		(duplicate_pad_numbers_are_jumpers no)
		(fp_line
			(start -0.7874 -0.4064)
			(end 0.7874 -0.4064)
			(stroke
				(width 0.1524)
				(type default)
			)
			(layer "F.SilkS")
		)
		(fp_line
			(start -0.7874 0.4064)
			(end -0.7874 -0.4064)
			(stroke
				(width 0.1524)
				(type default)
			)
			(layer "F.SilkS")
		)
		(fp_line
			(start 0.7874 -0.4064)
			(end 0.7874 0.4064)
			(stroke
				(width 0.1524)
				(type default)
			)
			(layer "F.SilkS")
		)
		(fp_line
			(start 0.7874 0.4064)
			(end -0.7874 0.4064)
			(stroke
				(width 0.1524)
				(type default)
			)
			(layer "F.SilkS")
		)
		(fp_line
			(start -0.67945 -0.305054)
			(end -0.12065 -0.305054)
			(stroke
				(width 0.1)
				(type default)
			)
			(layer "F.Fab")
		)
		(fp_line
			(start -0.67945 0.3048)
			(end -0.67945 -0.305054)
			(stroke
				(width 0.1)
				(type default)
			)
			(layer "F.Fab")
		)
		(fp_line
			(start -0.12065 -0.305054)
			(end -0.12065 -0.2794)
			(stroke
				(width 0.1)
				(type default)
			)
			(layer "F.Fab")
		)
		(fp_line
			(start -0.12065 -0.2794)
			(end 0.12065 -0.2794)
			(stroke
				(width 0.1)
				(type default)
			)
			(layer "F.Fab")
		)
		(fp_line
			(start -0.12065 0.2794)
			(end -0.12065 0.3048)
			(stroke
				(width 0.1)
				(type default)
			)
			(layer "F.Fab")
		)
		(fp_line
			(start -0.12065 0.3048)
			(end -0.67945 0.3048)
			(stroke
				(width 0.1)
				(type default)
			)
			(layer "F.Fab")
		)
		(fp_line
			(start 0.120396 0.2794)
			(end -0.12065 0.2794)
			(stroke
				(width 0.1)
				(type default)
			)
			(layer "F.Fab")
		)
		(fp_line
			(start 0.120396 0.3048)
			(end 0.120396 0.2794)
			(stroke
				(width 0.1)
				(type default)
			)
			(layer "F.Fab")
		)
		(fp_line
			(start 0.12065 -0.3048)
			(end 0.67945 -0.3048)
			(stroke
				(width 0.1)
				(type default)
			)
			(layer "F.Fab")
		)
		(fp_line
			(start 0.12065 -0.2794)
			(end 0.12065 -0.3048)
			(stroke
				(width 0.1)
				(type default)
			)
			(layer "F.Fab")
		)
		(fp_line
			(start 0.67945 -0.3048)
			(end 0.67945 0.3048)
			(stroke
				(width 0.1)
				(type default)
			)
			(layer "F.Fab")
		)
		(fp_line
			(start 0.67945 0.3048)
			(end 0.120396 0.3048)
			(stroke
				(width 0.1)
				(type default)
			)
			(layer "F.Fab")
		)
		(pad "1" smd circle
			(at -0.40005 0)
			(size 0 0)
			(layers "F.Cu" "F.Mask" "F.Paste")
			(net "SPI_BMC_TPM_CLK_R1")
		)
		(pad "2" smd circle
			(at 0.40005 0)
			(size 0 0)
			(layers "F.Cu" "F.Mask" "F.Paste")
			(net "SPI_BMC_TPM_CLK")
		)
	)
	(footprint ""
		(layer "F.Cu")
		(at 72.644 -16.256 90)
		(property "Reference" "C28"
			(at 0 0 90)
			(layer "F.SilkS")
			(hide yes)
			(effects
				(font
					(size 1.27 1.27)
				)
			)
		)
		(property "Value" ""
			(at 0 0 90)
			(layer "F.Fab")
			(effects
				(font
					(size 1.27 1.27)
				)
			)
		)
		(duplicate_pad_numbers_are_jumpers no)
		(fp_line
			(start 0.7874 -0.4064)
			(end 0.7874 0.4064)
			(stroke
				(width 0.1524)
				(type default)
			)
			(layer "F.SilkS")
		)
		(fp_line
			(start -0.7874 -0.4064)
			(end 0.7874 -0.4064)
			(stroke
				(width 0.1524)
				(type default)
			)
			(layer "F.SilkS")
		)
		(fp_line
			(start 0.7874 0.4064)
			(end -0.7874 0.4064)
			(stroke
				(width 0.1524)
				(type default)
			)
			(layer "F.SilkS")
		)
		(fp_line
			(start -0.7874 0.4064)
			(end -0.7874 -0.4064)
			(stroke
				(width 0.1524)
				(type default)
			)
			(layer "F.SilkS")
		)
		(fp_line
			(start -0.12065 -0.305054)
			(end -0.12065 -0.2794)
			(stroke
				(width 0.1)
				(type default)
			)
			(layer "F.Fab")
		)
		(fp_line
			(start -0.67945 -0.305054)
			(end -0.12065 -0.305054)
			(stroke
				(width 0.1)
				(type default)
			)
			(layer "F.Fab")
		)
		(fp_line
			(start 0.67945 -0.3048)
			(end 0.67945 0.3048)
			(stroke
				(width 0.1)
				(type default)
			)
			(layer "F.Fab")
		)
		(fp_line
			(start 0.12065 -0.3048)
			(end 0.67945 -0.3048)
			(stroke
				(width 0.1)
				(type default)
			)
			(layer "F.Fab")
		)
		(fp_line
			(start 0.12065 -0.2794)
			(end 0.12065 -0.3048)
			(stroke
				(width 0.1)
				(type default)
			)
			(layer "F.Fab")
		)
		(fp_line
			(start -0.12065 -0.2794)
			(end 0.12065 -0.2794)
			(stroke
				(width 0.1)
				(type default)
			)
			(layer "F.Fab")
		)
		(fp_line
			(start 0.120396 0.2794)
			(end -0.12065 0.2794)
			(stroke
				(width 0.1)
				(type default)
			)
			(layer "F.Fab")
		)
		(fp_line
			(start -0.12065 0.2794)
			(end -0.12065 0.3048)
			(stroke
				(width 0.1)
				(type default)
			)
			(layer "F.Fab")
		)
		(fp_line
			(start 0.67945 0.3048)
			(end 0.120396 0.3048)
			(stroke
				(width 0.1)
				(type default)
			)
			(layer "F.Fab")
		)
		(fp_line
			(start 0.120396 0.3048)
			(end 0.120396 0.2794)
			(stroke
				(width 0.1)
				(type default)
			)
			(layer "F.Fab")
		)
		(fp_line
			(start -0.12065 0.3048)
			(end -0.67945 0.3048)
			(stroke
				(width 0.1)
				(type default)
			)
			(layer "F.Fab")
		)
		(fp_line
			(start -0.67945 0.3048)
			(end -0.67945 -0.305054)
			(stroke
				(width 0.1)
				(type default)
			)
			(layer "F.Fab")
		)
		(pad "1" smd circle
			(at -0.40005 0 90)
			(size 0 0)
			(layers "F.Cu" "F.Mask" "F.Paste")
			(net "REAR_AC_PWR_BTN_N")
		)
		(pad "2" smd circle
			(at 0.40005 0 90)
			(size 0 0)
			(layers "F.Cu" "F.Mask" "F.Paste")
			(net "GND")
		)
	)
	(footprint ""
		(layer "F.Cu")
		(at 29.591 -22.9108 -90)
		(property "Reference" "D12"
			(at 1.27 -2.524252 90)
			(unlocked yes)
			(layer "F.SilkS")
			(effects
				(font
					(size 0.7874 0.5842)
					(thickness 0.1524)
				)
				(justify left)
			)
		)
		(property "Value" ""
			(at 0 0 270)
			(layer "F.Fab")
			(effects
				(font
					(size 1.27 1.27)
				)
			)
		)
		(duplicate_pad_numbers_are_jumpers no)
		(fp_line
			(start -1.7272 1.634744)
			(end -1.7272 -1.665224)
			(stroke
				(width 0.1524)
				(type default)
			)
			(layer "F.SilkS")
		)
		(fp_line
			(start 1.739646 1.634744)
			(end -1.7272 1.634744)
			(stroke
				(width 0.1524)
				(type default)
			)
			(layer "F.SilkS")
		)
		(fp_line
			(start 0 -0.930148)
			(end 0.571246 -1.665224)
			(stroke
				(width 0.1524)
				(type default)
			)
			(layer "F.SilkS")
		)
		(fp_line
			(start -1.7272 -1.665224)
			(end -0.5588 -1.665224)
			(stroke
				(width 0.1524)
				(type default)
			)
			(layer "F.SilkS")
		)
		(fp_line
			(start -0.5588 -1.665224)
			(end 0 -0.930148)
			(stroke
				(width 0.1524)
				(type default)
			)
			(layer "F.SilkS")
		)
		(fp_line
			(start 0.571246 -1.665224)
			(end 1.739646 -1.665224)
			(stroke
				(width 0.1524)
				(type default)
			)
			(layer "F.SilkS")
		)
		(fp_line
			(start 1.739646 -1.665224)
			(end 1.739646 1.634744)
			(stroke
				(width 0.1524)
				(type default)
			)
			(layer "F.SilkS")
		)
		(fp_poly
			(pts
				(xy -1.5748 -2.772664) (xy -0.8128 -2.772664) (xy -1.1938 -2.010664)
			)
			(stroke
				(width 0)
				(type default)
			)
			(fill yes)
			(layer "F.SilkS")
		)
		(fp_line
			(start -0.843788 1.534922)
			(end -0.843788 -1.565148)
			(stroke
				(width 0.1)
				(type default)
			)
			(layer "F.Fab")
		)
		(fp_line
			(start 0.856234 1.534922)
			(end -0.843788 1.534922)
			(stroke
				(width 0.1)
				(type default)
			)
			(layer "F.Fab")
		)
		(fp_line
			(start -0.843788 -1.565148)
			(end 0.856234 -1.565148)
			(stroke
				(width 0.1)
				(type default)
			)
			(layer "F.Fab")
		)
		(fp_line
			(start 0.856234 -1.565148)
			(end 0.856234 1.534922)
			(stroke
				(width 0.1)
				(type default)
			)
			(layer "F.Fab")
		)
		(fp_poly
			(pts
				(xy -2.747264 -0.5842) (xy -2.747264 -1.3462) (xy -1.985264 -0.9652)
			)
			(stroke
				(width 0)
				(type default)
			)
			(fill yes)
			(layer "F.Fab")
		)
		(pad "1" smd rect
			(at -1.1938 -0.9652 180)
			(size 0.5588 0.8128)
			(layers "F.Cu" "F.Mask" "F.Paste")
			(net "CRT_VCC5")
		)
		(pad "2" smd rect
			(at -1.1938 -0.01524 180)
			(size 0.5588 0.8128)
			(layers "F.Cu" "F.Mask" "F.Paste")
			(net "GND")
		)
		(pad "3" smd rect
			(at -1.1938 0.93472 180)
			(size 0.5588 0.8128)
			(layers "F.Cu" "F.Mask" "F.Paste")
			(net "CRT_VCC5")
		)
		(pad "4" smd rect
			(at 1.206246 0.93472 180)
			(size 0.5588 0.8128)
			(layers "F.Cu" "F.Mask" "F.Paste")
			(net "CRT_VCC5")
		)
		(pad "5" smd rect
			(at 1.206246 -0.01524 180)
			(size 0.5588 0.8128)
			(layers "F.Cu" "F.Mask" "F.Paste")
			(net "GND")
		)
		(pad "6" smd rect
			(at 1.206246 -0.9652 180)
			(size 0.5588 0.8128)
			(layers "F.Cu" "F.Mask" "F.Paste")
			(net "CRT_VCC5")
		)
	)
)
